# T6G (Grand Teton) — schematic netlist excerpt (pin names and nets, part order shuffled) for the footprints in the layout excerpt that follows; sources: Cadence DE-HDL packaged netlist, KiCad conversion of 04192023_DAF0TMB3IC0_F0TG_MB_C_brd_V02_OCP.brd

R131  Q_RES  10K 5% CHIP  pkg 0402LF  page 151 : A = P3V3_AUX ; B = UART_VCC_J8
PC161  Q_CAP  0.22UF 16V 10% X7R  pkg 0402  page 196 : A = SW_PVDDCR_CPU0_P0_BOOT6_RC ; B = SW_PVDDCR_CPU0_P0_PH6

(kicad_pcb
	(version 20260206)
	(generator "pcbnew")
	(generator_version "10.0")
	(general
		(thickness 1.6)
		(legacy_teardrops no)
	)
	(paper "A4")
	(title_block
		(title "04192023_DAF0TMB3IC0_F0TG_MB_C_brd_V02_OCP.brd")
		(comment 1 "Grand Teton / footprints 931-932 of 8354")
	)
	(layers
		(0 "F.Cu" signal "TOP")
		(4 "In1.Cu" signal "GND")
		(6 "In2.Cu" signal "IN1")
		(8 "In3.Cu" signal "GND1")
		(10 "In4.Cu" signal "IN2")
		(12 "In5.Cu" signal "GND2")
		(14 "In6.Cu" signal "IN3")
		(16 "In7.Cu" signal "GND3")
		(18 "In8.Cu" signal "VCC")
		(20 "In9.Cu" signal "VCC1")
		(22 "In10.Cu" signal "GND4")
		(24 "In11.Cu" signal "IN4")
		(26 "In12.Cu" signal "GND5")
		(28 "In13.Cu" signal "IN5")
		(30 "In14.Cu" signal "GND6")
		(32 "In15.Cu" signal "IN6")
		(34 "In16.Cu" signal "GND7")
		(2 "B.Cu" signal "BOTTOM")
		(9 "F.Adhes" user "F.Adhesive")
		(11 "B.Adhes" user "B.Adhesive")
		(13 "F.Paste" user "Package Geometry/Pastemask Top")
		(15 "B.Paste" user "Package Geometry/Pastemask Bottom")
		(5 "F.SilkS" user "Ref Des/Silkscreen Top")
		(7 "B.SilkS" user "Ref Des/Silkscreen Bottom")
		(1 "F.Mask" user "Board Geometry/Soldermask Top")
		(3 "B.Mask" user "Board Geometry/Soldermask Bottom")
		(17 "Dwgs.User" user "User.Drawings")
		(19 "Cmts.User" user "User.Comments")
		(21 "Eco1.User" user "User.Eco1")
		(23 "Eco2.User" user "User.Eco2")
		(25 "Edge.Cuts" user "Board Geometry/Outline")
		(27 "Margin" user)
		(31 "F.CrtYd" user "Package Geometry/Place Bound Top")
		(29 "B.CrtYd" user "Package Geometry/Place Bound Bottom")
		(35 "F.Fab" user "Ref Des/Assembly Top")
		(33 "B.Fab" user "Ref Des/Assembly Bottom")
	)
	(footprint ""
		(layer "F.Cu")
		(at 345.941904 -156.487622 90)
		(property "Reference" "PC161"
			(at 0 0 90)
			(layer "F.SilkS")
			(hide yes)
			(effects
				(font
					(size 1.27 1.27)
				)
			)
		)
		(property "Value" ""
			(at 0 0 90)
			(layer "F.Fab")
			(effects
				(font
					(size 1.27 1.27)
				)
			)
		)
		(duplicate_pad_numbers_are_jumpers no)
		(fp_line
			(start 0.7874 -0.4064)
			(end 0.7874 0.4064)
			(stroke
				(width 0.1524)
				(type default)
			)
			(layer "F.SilkS")
		)
		(fp_line
			(start -0.7874 -0.4064)
			(end 0.7874 -0.4064)
			(stroke
				(width 0.1524)
				(type default)
			)
			(layer "F.SilkS")
		)
		(fp_line
			(start 0.7874 0.4064)
			(end -0.7874 0.4064)
			(stroke
				(width 0.1524)
				(type default)
			)
			(layer "F.SilkS")
		)
		(fp_line
			(start -0.7874 0.4064)
			(end -0.7874 -0.4064)
			(stroke
				(width 0.1524)
				(type default)
			)
			(layer "F.SilkS")
		)
		(fp_line
			(start -0.12065 -0.305054)
			(end -0.12065 -0.2794)
			(stroke
				(width 0.1)
				(type default)
			)
			(layer "F.Fab")
		)
		(fp_line
			(start -0.67945 -0.305054)
			(end -0.12065 -0.305054)
			(stroke
				(width 0.1)
				(type default)
			)
			(layer "F.Fab")
		)
		(fp_line
			(start 0.67945 -0.3048)
			(end 0.67945 0.3048)
			(stroke
				(width 0.1)
				(type default)
			)
			(layer "F.Fab")
		)
		(fp_line
			(start 0.12065 -0.3048)
			(end 0.67945 -0.3048)
			(stroke
				(width 0.1)
				(type default)
			)
			(layer "F.Fab")
		)
		(fp_line
			(start 0.12065 -0.2794)
			(end 0.12065 -0.3048)
			(stroke
				(width 0.1)
				(type default)
			)
			(layer "F.Fab")
		)
		(fp_line
			(start -0.12065 -0.2794)
			(end 0.12065 -0.2794)
			(stroke
				(width 0.1)
				(type default)
			)
			(layer "F.Fab")
		)
		(fp_line
			(start 0.120396 0.2794)
			(end -0.12065 0.2794)
			(stroke
				(width 0.1)
				(type default)
			)
			(layer "F.Fab")
		)
		(fp_line
			(start -0.12065 0.2794)
			(end -0.12065 0.3048)
			(stroke
				(width 0.1)
				(type default)
			)
			(layer "F.Fab")
		)
		(fp_line
			(start 0.67945 0.3048)
			(end 0.120396 0.3048)
			(stroke
				(width 0.1)
				(type default)
			)
			(layer "F.Fab")
		)
		(fp_line
			(start 0.120396 0.3048)
			(end 0.120396 0.2794)
			(stroke
				(width 0.1)
				(type default)
			)
			(layer "F.Fab")
		)
		(fp_line
			(start -0.12065 0.3048)
			(end -0.67945 0.3048)
			(stroke
				(width 0.1)
				(type default)
			)
			(layer "F.Fab")
		)
		(fp_line
			(start -0.67945 0.3048)
			(end -0.67945 -0.305054)
			(stroke
				(width 0.1)
				(type default)
			)
			(layer "F.Fab")
		)
		(pad "1" smd circle
			(at -0.40005 0 90)
			(size 0 0)
			(layers "F.Cu" "F.Mask" "F.Paste")
			(net "SW_PVDDCR_CPU0_P0_BOOT6_RC")
		)
		(pad "2" smd circle
			(at 0.40005 0 90)
			(size 0 0)
			(layers "F.Cu" "F.Mask" "F.Paste")
			(net "SW_PVDDCR_CPU0_P0_PH6")
		)
	)
	(footprint ""
		(layer "F.Cu")
		(at 319.905888 -22.571456 -90)
		(property "Reference" "R131"
			(at 0 0 270)
			(layer "F.SilkS")
			(hide yes)
			(effects
				(font
					(size 1.27 1.27)
				)
			)
		)
		(property "Value" ""
			(at 0 0 270)
			(layer "F.Fab")
			(effects
				(font
					(size 1.27 1.27)
				)
			)
		)
		(duplicate_pad_numbers_are_jumpers no)
		(fp_line
			(start -0.7874 0.4064)
			(end -0.7874 -0.4064)
			(stroke
				(width 0.1524)
				(type default)
			)
			(layer "F.SilkS")
		)
		(fp_line
			(start 0.7874 0.4064)
			(end -0.7874 0.4064)
			(stroke
				(width 0.1524)
				(type default)
			)
			(layer "F.SilkS")
		)
		(fp_line
			(start -0.7874 -0.4064)
			(end 0.7874 -0.4064)
			(stroke
				(width 0.1524)
				(type default)
			)
			(layer "F.SilkS")
		)
		(fp_line
			(start 0.7874 -0.4064)
			(end 0.7874 0.4064)
			(stroke
				(width 0.1524)
				(type default)
			)
			(layer "F.SilkS")
		)
		(fp_line
			(start -0.67945 0.3048)
			(end -0.67945 -0.305054)
			(stroke
				(width 0.1)
				(type default)
			)
			(layer "F.Fab")
		)
		(fp_line
			(start -0.12065 0.3048)
			(end -0.67945 0.3048)
			(stroke
				(width 0.1)
				(type default)
			)
			(layer "F.Fab")
		)
		(fp_line
			(start 0.120396 0.3048)
			(end 0.120396 0.2794)
			(stroke
				(width 0.1)
				(type default)
			)
			(layer "F.Fab")
		)
		(fp_line
			(start 0.67945 0.3048)
			(end 0.120396 0.3048)
			(stroke
				(width 0.1)
				(type default)
			)
			(layer "F.Fab")
		)
		(fp_line
			(start -0.12065 0.2794)
			(end -0.12065 0.3048)
			(stroke
				(width 0.1)
				(type default)
			)
			(layer "F.Fab")
		)
		(fp_line
			(start 0.120396 0.2794)
			(end -0.12065 0.2794)
			(stroke
				(width 0.1)
				(type default)
			)
			(layer "F.Fab")
		)
		(fp_line
			(start -0.12065 -0.2794)
			(end 0.12065 -0.2794)
			(stroke
				(width 0.1)
				(type default)
			)
			(layer "F.Fab")
		)
		(fp_line
			(start 0.12065 -0.2794)
			(end 0.12065 -0.3048)
			(stroke
				(width 0.1)
				(type default)
			)
			(layer "F.Fab")
		)
		(fp_line
			(start 0.12065 -0.3048)
			(end 0.67945 -0.3048)
			(stroke
				(width 0.1)
				(type default)
			)
			(layer "F.Fab")
		)
		(fp_line
			(start 0.67945 -0.3048)
			(end 0.67945 0.3048)
			(stroke
				(width 0.1)
				(type default)
			)
			(layer "F.Fab")
		)
		(fp_line
			(start -0.67945 -0.305054)
			(end -0.12065 -0.305054)
			(stroke
				(width 0.1)
				(type default)
			)
			(layer "F.Fab")
		)
		(fp_line
			(start -0.12065 -0.305054)
			(end -0.12065 -0.2794)
			(stroke
				(width 0.1)
				(type default)
			)
			(layer "F.Fab")
		)
		(pad "1" smd circle
			(at -0.40005 0 270)
			(size 0 0)
			(layers "F.Cu" "F.Mask" "F.Paste")
			(net "P3V3_AUX")
		)
		(pad "2" smd circle
			(at 0.40005 0 270)
			(size 0 0)
			(layers "F.Cu" "F.Mask" "F.Paste")
			(net "UART_VCC_J8")
		)
	)
)
